(kicad_pcb
	(version 20260206)
	(generator "pcbnew")
	(generator_version "10.0")
	(general
		(thickness 1.6)
		(legacy_teardrops no)
	)
	(paper "A4")
	(title_block
		(title "Bryce Canyon_IOM_M2_16342-2_OCP.brd")
		(comment 1 "Bryce Canyon / footprints 813-820 of 1146")
	)
	(layers
		(0 "F.Cu" signal "TOP")
		(4 "In1.Cu" signal "L2GND")
		(6 "In2.Cu" signal "L3")
		(8 "In3.Cu" signal "L4VCC")
		(10 "In4.Cu" signal "L5VCC")
		(12 "In5.Cu" signal "L6")
		(14 "In6.Cu" signal "L7GND")
		(2 "B.Cu" signal "BOTTOM")
		(9 "F.Adhes" user "F.Adhesive")
		(11 "B.Adhes" user "B.Adhesive")
		(13 "F.Paste" user "Package Geometry/Pastemask Top")
		(15 "B.Paste" user "Package Geometry/Pastemask Bottom")
		(5 "F.SilkS" user "Ref Des/Silkscreen Top")
		(7 "B.SilkS" user "Ref Des/Silkscreen Bottom")
		(1 "F.Mask" user "Board Geometry/Soldermask Top")
		(3 "B.Mask" user "Board Geometry/Soldermask Bottom")
		(17 "Dwgs.User" user "User.Drawings")
		(19 "Cmts.User" user "User.Comments")
		(21 "Eco1.User" user "User.Eco1")
		(23 "Eco2.User" user "User.Eco2")
		(25 "Edge.Cuts" user "Board Geometry/Outline")
		(27 "Margin" user)
		(31 "F.CrtYd" user "Package Geometry/Place Bound Top")
		(29 "B.CrtYd" user "Package Geometry/Place Bound Bottom")
		(35 "F.Fab" user "Ref Des/Assembly Top")
		(33 "B.Fab" user "Ref Des/Assembly Bottom")
	)
	(footprint ""
		(layer "B.Cu")
		(at 218.823794 -91.481402)
		(property "Reference" "R837"
			(at 0 0 0)
			(layer "B.SilkS")
			(hide yes)
			(effects
				(font
					(size 1.27 1.27)
				)
				(justify mirror)
			)
		)
		(property "Value" "2D7R3-GP"
			(at 0.0254 -2.5146 0)
			(unlocked yes)
			(layer "B.Fab")
			(hide yes)
			(effects
				(font
					(size 1.016 1.016)
					(thickness 0.1524)
				)
				(justify mirror)
			)
		)
		(property "Device Type" "R603H22"
			(at 0.0254 -4.0386 0)
			(unlocked yes)
			(layer "B.Fab")
			(hide yes)
			(effects
				(font
					(size 1.016 1.016)
					(thickness 0.1524)
				)
				(justify mirror)
			)
		)
		(duplicate_pad_numbers_are_jumpers no)
		(fp_line
			(start -0.2032 0)
			(end -0.4826 0)
			(stroke
				(width 0.2032)
				(type default)
			)
			(layer "B.SilkS")
		)
		(fp_line
			(start 0.4826 0)
			(end 0.2032 0)
			(stroke
				(width 0.2032)
				(type default)
			)
			(layer "B.SilkS")
		)
		(fp_rect
			(start 0.5842 1.3335)
			(end -0.5842 -1.3335)
			(stroke
				(width 0)
				(type default)
			)
			(fill no)
			(layer "B.CrtYd")
		)
		(fp_rect
			(start 0.5842 1.3335)
			(end -0.5842 -1.3335)
			(stroke
				(width 0)
				(type default)
			)
			(fill no)
			(layer "B.Fab")
		)
		(pad "1" smd custom
			(at 0 -0.762 180)
			(size 0.2159 0.2159)
			(layers "B.Cu" "B.Mask" "B.Paste")
			(net "P3V3_M2_VBST")
			(options
				(clearance outline)
				(anchor circle)
			)
			(primitives
				(gr_poly
					(pts
						(arc
							(start -0.3302 0.4318)
							(mid -0.402042 0.402042)
							(end -0.4318 0.3302)
						)
						(arc
							(start -0.4318 -0.3302)
							(mid -0.402042 -0.402042)
							(end -0.3302 -0.4318)
						)
						(arc
							(start 0.3302 -0.4318)
							(mid 0.402042 -0.402042)
							(end 0.4318 -0.3302)
						)
						(arc
							(start 0.4318 0.3302)
							(mid 0.402042 0.402042)
							(end 0.3302 0.4318)
						)
					)
					(width 0)
					(fill yes)
				)
			)
		)
		(pad "2" smd custom
			(at 0 0.762 180)
			(size 0.2159 0.2159)
			(layers "B.Cu" "B.Mask" "B.Paste")
			(net "P3V3_M2_VBST_RC")
			(options
				(clearance outline)
				(anchor circle)
			)
			(primitives
				(gr_poly
					(pts
						(arc
							(start -0.3302 0.4318)
							(mid -0.402042 0.402042)
							(end -0.4318 0.3302)
						)
						(arc
							(start -0.4318 -0.3302)
							(mid -0.402042 -0.402042)
							(end -0.3302 -0.4318)
						)
						(arc
							(start 0.3302 -0.4318)
							(mid 0.402042 -0.402042)
							(end 0.4318 -0.3302)
						)
						(arc
							(start 0.4318 0.3302)
							(mid 0.402042 0.402042)
							(end 0.3302 0.4318)
						)
					)
					(width 0)
					(fill yes)
				)
			)
		)
	)
	(footprint ""
		(layer "B.Cu")
		(at 224.989644 -72.07123 90)
		(property "Reference" "C655"
			(at 0 0 90)
			(layer "B.SilkS")
			(hide yes)
			(effects
				(font
					(size 1.27 1.27)
				)
				(justify mirror)
			)
		)
		(property "Value" "SC10U6D3V5KX-4GP"
			(at 0.0762 -6.1214 90)
			(unlocked yes)
			(layer "B.Fab")
			(hide yes)
			(effects
				(font
					(size 1.016 1.016)
					(thickness 0.1524)
				)
				(justify mirror)
			)
		)
		(property "Device Type" "C805H58"
			(at 0.0762 -8.1534 90)
			(unlocked yes)
			(layer "B.Fab")
			(hide yes)
			(effects
				(font
					(size 1.016 1.016)
					(thickness 0.1524)
				)
				(justify mirror)
			)
		)
		(duplicate_pad_numbers_are_jumpers no)
		(fp_line
			(start -0.635 0)
			(end 0.635 0)
			(stroke
				(width 0.508)
				(type default)
			)
			(layer "B.SilkS")
		)
		(fp_rect
			(start 0.9652 1.778)
			(end -0.9652 -1.778)
			(stroke
				(width 0)
				(type default)
			)
			(fill no)
			(layer "B.CrtYd")
		)
		(fp_poly
			(pts
				(xy 0.9652 -1.778) (xy -0.9652 -1.778) (xy -0.9652 1.778) (xy 0.9652 1.778)
			)
			(stroke
				(width 0)
				(type default)
			)
			(fill no)
			(layer "B.Fab")
		)
		(pad "1" smd rect
			(at 0 -0.9652 270)
			(size 1.397 1.143)
			(layers "B.Cu" "B.Mask" "B.Paste")
			(net "P3V3_M2")
		)
		(pad "2" smd rect
			(at 0 0.9652 270)
			(size 1.397 1.143)
			(layers "B.Cu" "B.Mask" "B.Paste")
			(net "GND")
		)
	)
	(footprint ""
		(layer "B.Cu")
		(at 175.294036 -130.732784 180)
		(property "Reference" "C616"
			(at 0 0 0)
			(layer "B.SilkS")
			(hide yes)
			(effects
				(font
					(size 1.27 1.27)
				)
				(justify mirror)
			)
		)
		(property "Value" "SCD1U16V2KX-3GP"
			(at -1.1811 -2.7051 180)
			(unlocked yes)
			(layer "B.Fab")
			(hide yes)
			(effects
				(font
					(size 1.016 1.016)
					(thickness 0.1524)
				)
				(justify mirror)
			)
		)
		(property "Device Type" "C402H22"
			(at -1.1811 -4.2291 180)
			(unlocked yes)
			(layer "B.Fab")
			(hide yes)
			(effects
				(font
					(size 1.016 1.016)
					(thickness 0.1524)
				)
				(justify mirror)
			)
		)
		(duplicate_pad_numbers_are_jumpers no)
		(fp_rect
			(start 0.4318 0.9525)
			(end -0.4318 -0.9525)
			(stroke
				(width 0)
				(type default)
			)
			(fill no)
			(layer "B.CrtYd")
		)
		(fp_rect
			(start 0.4318 0.9525)
			(end -0.4318 -0.9525)
			(stroke
				(width 0)
				(type default)
			)
			(fill no)
			(layer "B.Fab")
		)
		(pad "1" smd custom
			(at 0 -0.4445)
			(size 0.1524 0.1524)
			(layers "B.Cu" "B.Mask" "B.Paste")
			(net "P3V3_M2")
			(options
				(clearance outline)
				(anchor circle)
			)
			(primitives
				(gr_poly
					(pts
						(arc
							(start 0.3048 0.2032)
							(mid 0.275042 0.275042)
							(end 0.2032 0.3048)
						)
						(arc
							(start -0.2032 0.3048)
							(mid -0.275042 0.275042)
							(end -0.3048 0.2032)
						)
						(arc
							(start -0.3048 -0.2032)
							(mid -0.275042 -0.275042)
							(end -0.2032 -0.3048)
						)
						(arc
							(start 0.2032 -0.3048)
							(mid 0.275042 -0.275042)
							(end 0.3048 -0.2032)
						)
					)
					(width 0)
					(fill yes)
				)
			)
		)
		(pad "2" smd custom
			(at 0 0.4445)
			(size 0.1524 0.1524)
			(layers "B.Cu" "B.Mask" "B.Paste")
			(net "GND")
			(options
				(clearance outline)
				(anchor circle)
			)
			(primitives
				(gr_poly
					(pts
						(arc
							(start 0.3048 0.2032)
							(mid 0.275042 0.275042)
							(end 0.2032 0.3048)
						)
						(arc
							(start -0.2032 0.3048)
							(mid -0.275042 0.275042)
							(end -0.3048 0.2032)
						)
						(arc
							(start -0.3048 -0.2032)
							(mid -0.275042 -0.275042)
							(end -0.2032 -0.3048)
						)
						(arc
							(start 0.2032 -0.3048)
							(mid 0.275042 -0.275042)
							(end 0.3048 -0.2032)
						)
					)
					(width 0)
					(fill yes)
				)
			)
		)
	)
	(footprint ""
		(layer "B.Cu")
		(at 61.7474 -138.0998 -90)
		(property "Reference" "R185"
			(at 0 0 90)
			(layer "B.SilkS")
			(hide yes)
			(effects
				(font
					(size 1.27 1.27)
				)
				(justify mirror)
			)
		)
		(property "Value" "2K2R2F-GP"
			(at -0.064008 -3.993896 270)
			(unlocked yes)
			(layer "B.Fab")
			(hide yes)
			(effects
				(font
					(size 1.016 1.016)
					(thickness 0.1524)
				)
				(justify mirror)
			)
		)
		(property "Device Type" "R402H16"
			(at -0.064008 -5.517896 270)
			(unlocked yes)
			(layer "B.Fab")
			(hide yes)
			(effects
				(font
					(size 1.016 1.016)
					(thickness 0.1524)
				)
				(justify mirror)
			)
		)
		(duplicate_pad_numbers_are_jumpers no)
		(fp_line
			(start -0.508 -0.9398)
			(end 0.508 -0.9398)
			(stroke
				(width 0.1524)
				(type default)
			)
			(layer "B.SilkS")
		)
		(fp_line
			(start 0.508 -0.9398)
			(end 0.508 0.9398)
			(stroke
				(width 0.1524)
				(type default)
			)
			(layer "B.SilkS")
		)
		(fp_rect
			(start 0.508 0.9398)
			(end -0.508 -0.9398)
			(stroke
				(width 0)
				(type default)
			)
			(fill no)
			(layer "B.CrtYd")
		)
		(fp_rect
			(start 0.508 0.9398)
			(end -0.508 -0.9398)
			(stroke
				(width 0)
				(type default)
			)
			(fill no)
			(layer "B.Fab")
		)
		(pad "1" smd custom
			(at 0 -0.4445 90)
			(size 0.1397 0.1397)
			(layers "B.Cu" "B.Mask" "B.Paste")
			(net "I2C_M2_2_SCL")
			(options
				(clearance outline)
				(anchor circle)
			)
			(primitives
				(gr_poly
					(pts
						(arc
							(start -0.1778 0.2794)
							(mid -0.249642 0.249642)
							(end -0.2794 0.1778)
						)
						(arc
							(start -0.2794 -0.1778)
							(mid -0.249642 -0.249642)
							(end -0.1778 -0.2794)
						)
						(arc
							(start 0.1778 -0.2794)
							(mid 0.249642 -0.249642)
							(end 0.2794 -0.1778)
						)
						(arc
							(start 0.2794 0.1778)
							(mid 0.249642 0.249642)
							(end 0.1778 0.2794)
						)
					)
					(width 0)
					(fill yes)
				)
			)
		)
		(pad "2" smd custom
			(at 0 0.4445 90)
			(size 0.1397 0.1397)
			(layers "B.Cu" "B.Mask" "B.Paste")
			(net "P3V3_STBY")
			(options
				(clearance outline)
				(anchor circle)
			)
			(primitives
				(gr_poly
					(pts
						(arc
							(start -0.1778 0.2794)
							(mid -0.249642 0.249642)
							(end -0.2794 0.1778)
						)
						(arc
							(start -0.2794 -0.1778)
							(mid -0.249642 -0.249642)
							(end -0.1778 -0.2794)
						)
						(arc
							(start 0.1778 -0.2794)
							(mid 0.249642 -0.249642)
							(end 0.2794 -0.1778)
						)
						(arc
							(start 0.2794 0.1778)
							(mid 0.249642 0.249642)
							(end 0.1778 0.2794)
						)
					)
					(width 0)
					(fill yes)
				)
			)
		)
	)
	(footprint ""
		(layer "B.Cu")
		(at 38.419278 -143.058642)
		(property "Reference" "C58"
			(at 0 0 0)
			(layer "B.SilkS")
			(hide yes)
			(effects
				(font
					(size 1.27 1.27)
				)
				(justify mirror)
			)
		)
		(property "Value" "SC1U16V3KX-5GP"
			(at 0 -2.8194 0)
			(unlocked yes)
			(layer "B.Fab")
			(hide yes)
			(effects
				(font
					(size 1.016 1.016)
					(thickness 0.1524)
				)
				(justify mirror)
			)
		)
		(property "Device Type" "C603H36"
			(at 0 -4.3434 0)
			(unlocked yes)
			(layer "B.Fab")
			(hide yes)
			(effects
				(font
					(size 1.016 1.016)
					(thickness 0.1524)
				)
				(justify mirror)
			)
		)
		(duplicate_pad_numbers_are_jumpers no)
		(fp_line
			(start -0.508 0)
			(end 0.508 0)
			(stroke
				(width 0.2032)
				(type default)
			)
			(layer "B.SilkS")
		)
		(fp_rect
			(start 0.5842 1.3335)
			(end -0.5842 -1.3335)
			(stroke
				(width 0)
				(type default)
			)
			(fill no)
			(layer "B.CrtYd")
		)
		(fp_rect
			(start 0.5842 1.3335)
			(end -0.5842 -1.3335)
			(stroke
				(width 0)
				(type default)
			)
			(fill no)
			(layer "B.Fab")
		)
		(pad "1" smd custom
			(at 0 -0.762 180)
			(size 0.2159 0.2159)
			(layers "B.Cu" "B.Mask" "B.Paste")
			(net "P1V2_STBY")
			(options
				(clearance outline)
				(anchor circle)
			)
			(primitives
				(gr_poly
					(pts
						(arc
							(start -0.3302 0.4318)
							(mid -0.402042 0.402042)
							(end -0.4318 0.3302)
						)
						(arc
							(start -0.4318 -0.3302)
							(mid -0.402042 -0.402042)
							(end -0.3302 -0.4318)
						)
						(arc
							(start 0.3302 -0.4318)
							(mid 0.402042 -0.402042)
							(end 0.4318 -0.3302)
						)
						(arc
							(start 0.4318 0.3302)
							(mid 0.402042 0.402042)
							(end 0.3302 0.4318)
						)
					)
					(width 0)
					(fill yes)
				)
			)
		)
		(pad "2" smd custom
			(at 0 0.762 180)
			(size 0.2159 0.2159)
			(layers "B.Cu" "B.Mask" "B.Paste")
			(net "GND")
			(options
				(clearance outline)
				(anchor circle)
			)
			(primitives
				(gr_poly
					(pts
						(arc
							(start -0.3302 0.4318)
							(mid -0.402042 0.402042)
							(end -0.4318 0.3302)
						)
						(arc
							(start -0.4318 -0.3302)
							(mid -0.402042 -0.402042)
							(end -0.3302 -0.4318)
						)
						(arc
							(start 0.3302 -0.4318)
							(mid 0.402042 -0.402042)
							(end 0.4318 -0.3302)
						)
						(arc
							(start 0.4318 0.3302)
							(mid 0.402042 0.402042)
							(end 0.3302 0.4318)
						)
					)
					(width 0)
					(fill yes)
				)
			)
		)
	)
	(footprint ""
		(layer "B.Cu")
		(at 120.123966 -6.5532 90)
		(property "Reference" "C132"
			(at 0 0 90)
			(layer "B.SilkS")
			(hide yes)
			(effects
				(font
					(size 1.27 1.27)
				)
				(justify mirror)
			)
		)
		(property "Value" "SC22UF16V6KX-GP"
			(at 0 -6.8072 90)
			(unlocked yes)
			(layer "B.Fab")
			(hide yes)
			(effects
				(font
					(size 1.016 1.016)
					(thickness 0.1524)
				)
				(justify mirror)
			)
		)
		(property "Device Type" "C1206H75"
			(at 0 -8.7122 90)
			(unlocked yes)
			(layer "B.Fab")
			(hide yes)
			(effects
				(font
					(size 1.016 1.016)
					(thickness 0.1524)
				)
				(justify mirror)
			)
		)
		(duplicate_pad_numbers_are_jumpers no)
		(fp_line
			(start 1.016 -2.2352)
			(end 1.016 -0.8382)
			(stroke
				(width 0.1524)
				(type default)
			)
			(layer "B.SilkS")
		)
		(fp_line
			(start -1.016 -2.2352)
			(end 1.016 -2.2352)
			(stroke
				(width 0.1524)
				(type default)
			)
			(layer "B.SilkS")
		)
		(fp_line
			(start -1.016 -2.2352)
			(end -1.016 -0.8382)
			(stroke
				(width 0.1524)
				(type default)
			)
			(layer "B.SilkS")
		)
		(fp_line
			(start -1.016 0.8382)
			(end -1.016 2.2352)
			(stroke
				(width 0.1524)
				(type default)
			)
			(layer "B.SilkS")
		)
		(fp_line
			(start 1.016 2.2352)
			(end 1.016 0.8128)
			(stroke
				(width 0.1524)
				(type default)
			)
			(layer "B.SilkS")
		)
		(fp_line
			(start -1.016 2.2352)
			(end 1.016 2.2352)
			(stroke
				(width 0.1524)
				(type default)
			)
			(layer "B.SilkS")
		)
		(fp_rect
			(start 1.0922 2.3114)
			(end -1.0922 -2.3114)
			(stroke
				(width 0)
				(type default)
			)
			(fill no)
			(layer "B.CrtYd")
		)
		(fp_poly
			(pts
				(xy 1.0922 -2.3114) (xy -1.0922 -2.3114) (xy -1.0922 2.3114) (xy 1.0922 2.3114)
			)
			(stroke
				(width 0)
				(type default)
			)
			(fill no)
			(layer "B.Fab")
		)
		(pad "1" smd rect
			(at 0 -1.397 270)
			(size 1.651 1.27)
			(layers "B.Cu" "B.Mask" "B.Paste")
			(net "MB0_HS_ENABLE")
		)
		(pad "2" smd rect
			(at 0 1.397 270)
			(size 1.651 1.27)
			(layers "B.Cu" "B.Mask" "B.Paste")
			(net "GND")
		)
	)
	(footprint ""
		(layer "B.Cu")
		(at 57.3278 -145.2626 -90)
		(property "Reference" "R361"
			(at 0 0 90)
			(layer "B.SilkS")
			(hide yes)
			(effects
				(font
					(size 1.27 1.27)
				)
				(justify mirror)
			)
		)
		(property "Value" "10KR2F-2-GP"
			(at -0.064008 -3.993896 270)
			(unlocked yes)
			(layer "B.Fab")
			(hide yes)
			(effects
				(font
					(size 1.016 1.016)
					(thickness 0.1524)
				)
				(justify mirror)
			)
		)
		(property "Device Type" "R402H16"
			(at -0.064008 -5.517896 270)
			(unlocked yes)
			(layer "B.Fab")
			(hide yes)
			(effects
				(font
					(size 1.016 1.016)
					(thickness 0.1524)
				)
				(justify mirror)
			)
		)
		(duplicate_pad_numbers_are_jumpers no)
		(fp_line
			(start -0.508 -0.9398)
			(end 0.508 -0.9398)
			(stroke
				(width 0.1524)
				(type default)
			)
			(layer "B.SilkS")
		)
		(fp_line
			(start 0.508 -0.9398)
			(end 0.508 0.9398)
			(stroke
				(width 0.1524)
				(type default)
			)
			(layer "B.SilkS")
		)
		(fp_rect
			(start 0.508 0.9398)
			(end -0.508 -0.9398)
			(stroke
				(width 0)
				(type default)
			)
			(fill no)
			(layer "B.CrtYd")
		)
		(fp_rect
			(start 0.508 0.9398)
			(end -0.508 -0.9398)
			(stroke
				(width 0)
				(type default)
			)
			(fill no)
			(layer "B.Fab")
		)
		(pad "1" smd custom
			(at 0 -0.4445 90)
			(size 0.1397 0.1397)
			(layers "B.Cu" "B.Mask" "B.Paste")
			(net "P3V3_STBY")
			(options
				(clearance outline)
				(anchor circle)
			)
			(primitives
				(gr_poly
					(pts
						(arc
							(start -0.1778 0.2794)
							(mid -0.249642 0.249642)
							(end -0.2794 0.1778)
						)
						(arc
							(start -0.2794 -0.1778)
							(mid -0.249642 -0.249642)
							(end -0.1778 -0.2794)
						)
						(arc
							(start 0.1778 -0.2794)
							(mid 0.249642 -0.249642)
							(end 0.2794 -0.1778)
						)
						(arc
							(start 0.2794 0.1778)
							(mid 0.249642 0.249642)
							(end 0.1778 0.2794)
						)
					)
					(width 0)
					(fill yes)
				)
			)
		)
		(pad "2" smd custom
			(at 0 0.4445 90)
			(size 0.1397 0.1397)
			(layers "B.Cu" "B.Mask" "B.Paste")
			(net "JTAG_BMC_TDO")
			(options
				(clearance outline)
				(anchor circle)
			)
			(primitives
				(gr_poly
					(pts
						(arc
							(start -0.1778 0.2794)
							(mid -0.249642 0.249642)
							(end -0.2794 0.1778)
						)
						(arc
							(start -0.2794 -0.1778)
							(mid -0.249642 -0.249642)
							(end -0.1778 -0.2794)
						)
						(arc
							(start 0.1778 -0.2794)
							(mid 0.249642 -0.249642)
							(end 0.2794 -0.1778)
						)
						(arc
							(start 0.2794 0.1778)
							(mid 0.249642 0.249642)
							(end 0.1778 0.2794)
						)
					)
					(width 0)
					(fill yes)
				)
			)
		)
	)
	(footprint ""
		(layer "B.Cu")
		(at 53.877972 -119.200422 180)
		(property "Reference" "R282"
			(at 0 0 0)
			(layer "B.SilkS")
			(hide yes)
			(effects
				(font
					(size 1.27 1.27)
				)
				(justify mirror)
			)
		)
		(property "Value" "4K7R2F-GP"
			(at -0.064008 -3.993896 180)
			(unlocked yes)
			(layer "B.Fab")
			(hide yes)
			(effects
				(font
					(size 1.016 1.016)
					(thickness 0.1524)
				)
				(justify mirror)
			)
		)
		(property "Device Type" "R402H16"
			(at -0.064008 -5.517896 180)
			(unlocked yes)
			(layer "B.Fab")
			(hide yes)
			(effects
				(font
					(size 1.016 1.016)
					(thickness 0.1524)
				)
				(justify mirror)
			)
		)
		(duplicate_pad_numbers_are_jumpers no)
		(fp_line
			(start 0.508 -0.9398)
			(end 0.508 0.9398)
			(stroke
				(width 0.1524)
				(type default)
			)
			(layer "B.SilkS")
		)
		(fp_line
			(start -0.508 -0.9398)
			(end 0.508 -0.9398)
			(stroke
				(width 0.1524)
				(type default)
			)
			(layer "B.SilkS")
		)
		(fp_rect
			(start 0.508 0.9398)
			(end -0.508 -0.9398)
			(stroke
				(width 0)
				(type default)
			)
			(fill no)
			(layer "B.CrtYd")
		)
		(fp_rect
			(start 0.508 0.9398)
			(end -0.508 -0.9398)
			(stroke
				(width 0)
				(type default)
			)
			(fill no)
			(layer "B.Fab")
		)
		(pad "1" smd custom
			(at 0 -0.4445)
			(size 0.1397 0.1397)
			(layers "B.Cu" "B.Mask" "B.Paste")
			(net "P3V3_STBY")
			(options
				(clearance outline)
				(anchor circle)
			)
			(primitives
				(gr_poly
					(pts
						(arc
							(start -0.1778 0.2794)
							(mid -0.249642 0.249642)
							(end -0.2794 0.1778)
						)
						(arc
							(start -0.2794 -0.1778)
							(mid -0.249642 -0.249642)
							(end -0.1778 -0.2794)
						)
						(arc
							(start 0.1778 -0.2794)
							(mid 0.249642 -0.249642)
							(end 0.2794 -0.1778)
						)
						(arc
							(start 0.2794 0.1778)
							(mid 0.249642 0.249642)
							(end 0.1778 0.2794)
						)
					)
					(width 0)
					(fill yes)
				)
			)
		)
		(pad "2" smd custom
			(at 0 0.4445)
			(size 0.1397 0.1397)
			(layers "B.Cu" "B.Mask" "B.Paste")
			(net "TEMP_3_A0")
			(options
				(clearance outline)
				(anchor circle)
			)
			(primitives
				(gr_poly
					(pts
						(arc
							(start -0.1778 0.2794)
							(mid -0.249642 0.249642)
							(end -0.2794 0.1778)
						)
						(arc
							(start -0.2794 -0.1778)
							(mid -0.249642 -0.249642)
							(end -0.1778 -0.2794)
						)
						(arc
							(start 0.1778 -0.2794)
							(mid 0.249642 -0.249642)
							(end 0.2794 -0.1778)
						)
						(arc
							(start 0.2794 0.1778)
							(mid 0.249642 0.249642)
							(end 0.1778 0.2794)
						)
					)
					(width 0)
					(fill yes)
				)
			)
		)
	)
)
